(kicad_pcb
	(version 20260206)
	(generator "pcbnew")
	(generator_version "10.0")
	(general
		(thickness 1.6)
		(legacy_teardrops no)
	)
	(paper "A4")
	(title_block
		(title "Bryce Canyon_SCC_16316-1_OCP.brd")
		(comment 1 "Bryce Canyon / footprints 37-44 of 1561")
	)
	(layers
		(0 "F.Cu" signal "TOP")
		(4 "In1.Cu" signal "L2GND")
		(6 "In2.Cu" signal "L3")
		(8 "In3.Cu" signal "L4VCC")
		(10 "In4.Cu" signal "L5VCC")
		(12 "In5.Cu" signal "L6")
		(14 "In6.Cu" signal "L7GND")
		(2 "B.Cu" signal "BOTTOM")
		(9 "F.Adhes" user "F.Adhesive")
		(11 "B.Adhes" user "B.Adhesive")
		(13 "F.Paste" user "Package Geometry/Pastemask Top")
		(15 "B.Paste" user "Package Geometry/Pastemask Bottom")
		(5 "F.SilkS" user "Ref Des/Silkscreen Top")
		(7 "B.SilkS" user "Ref Des/Silkscreen Bottom")
		(1 "F.Mask" user "Board Geometry/Soldermask Top")
		(3 "B.Mask" user "Board Geometry/Soldermask Bottom")
		(17 "Dwgs.User" user "User.Drawings")
		(19 "Cmts.User" user "User.Comments")
		(21 "Eco1.User" user "User.Eco1")
		(23 "Eco2.User" user "User.Eco2")
		(25 "Edge.Cuts" user "Board Geometry/Outline")
		(27 "Margin" user)
		(31 "F.CrtYd" user "Package Geometry/Place Bound Top")
		(29 "B.CrtYd" user "Package Geometry/Place Bound Bottom")
		(35 "F.Fab" user "Ref Des/Assembly Top")
		(33 "B.Fab" user "Ref Des/Assembly Bottom")
	)
	(footprint ""
		(layer "F.Cu")
		(at 111.125 -86.995 180)
		(property "Reference" "R136"
			(at 0 0 180)
			(layer "F.SilkS")
			(hide yes)
			(effects
				(font
					(size 1.27 1.27)
				)
			)
		)
		(property "Value" "4K75R2F-1-GP"
			(at 0.064008 -3.993896 180)
			(unlocked yes)
			(layer "F.Fab")
			(hide yes)
			(effects
				(font
					(size 1.016 1.016)
					(thickness 0.1524)
				)
			)
		)
		(property "Device Type" "R402H16"
			(at 0.064008 -5.517896 180)
			(unlocked yes)
			(layer "F.Fab")
			(hide yes)
			(effects
				(font
					(size 1.016 1.016)
					(thickness 0.1524)
				)
			)
		)
		(duplicate_pad_numbers_are_jumpers no)
		(fp_line
			(start 0.508 -0.9398)
			(end -0.508 -0.9398)
			(stroke
				(width 0.1524)
				(type default)
			)
			(layer "F.SilkS")
		)
		(fp_line
			(start -0.508 -0.9398)
			(end -0.508 0.9398)
			(stroke
				(width 0.1524)
				(type default)
			)
			(layer "F.SilkS")
		)
		(fp_rect
			(start -0.508 0.9398)
			(end 0.508 -0.9398)
			(stroke
				(width 0)
				(type default)
			)
			(fill no)
			(layer "F.CrtYd")
		)
		(fp_rect
			(start -0.508 0.9398)
			(end 0.508 -0.9398)
			(stroke
				(width 0)
				(type default)
			)
			(fill no)
			(layer "F.Fab")
		)
		(pad "1" smd custom
			(at 0 -0.4445 180)
			(size 0.1397 0.1397)
			(layers "F.Cu" "F.Mask" "F.Paste")
			(net "EXP_XM_OE_N")
			(options
				(clearance outline)
				(anchor circle)
			)
			(primitives
				(gr_poly
					(pts
						(arc
							(start -0.1778 -0.2794)
							(mid -0.249642 -0.249642)
							(end -0.2794 -0.1778)
						)
						(arc
							(start -0.2794 0.1778)
							(mid -0.249642 0.249642)
							(end -0.1778 0.2794)
						)
						(arc
							(start 0.1778 0.2794)
							(mid 0.249642 0.249642)
							(end 0.2794 0.1778)
						)
						(arc
							(start 0.2794 -0.1778)
							(mid 0.249642 -0.249642)
							(end 0.1778 -0.2794)
						)
					)
					(width 0)
					(fill yes)
				)
			)
		)
		(pad "2" smd custom
			(at 0 0.4445 180)
			(size 0.1397 0.1397)
			(layers "F.Cu" "F.Mask" "F.Paste")
			(net "P1V8_E")
			(options
				(clearance outline)
				(anchor circle)
			)
			(primitives
				(gr_poly
					(pts
						(arc
							(start -0.1778 -0.2794)
							(mid -0.249642 -0.249642)
							(end -0.2794 -0.1778)
						)
						(arc
							(start -0.2794 0.1778)
							(mid -0.249642 0.249642)
							(end -0.1778 0.2794)
						)
						(arc
							(start 0.1778 0.2794)
							(mid 0.249642 0.249642)
							(end 0.2794 0.1778)
						)
						(arc
							(start 0.2794 -0.1778)
							(mid 0.249642 -0.249642)
							(end 0.1778 -0.2794)
						)
					)
					(width 0)
					(fill yes)
				)
			)
		)
	)
	(footprint ""
		(layer "F.Cu")
		(at 171.323 -103.505 -90)
		(property "Reference" "R605"
			(at 0 0 270)
			(layer "F.SilkS")
			(hide yes)
			(effects
				(font
					(size 1.27 1.27)
				)
			)
		)
		(property "Value" "4K7R2F-GP"
			(at 0.064008 -3.993896 270)
			(unlocked yes)
			(layer "F.Fab")
			(hide yes)
			(effects
				(font
					(size 1.016 1.016)
					(thickness 0.1524)
				)
			)
		)
		(property "Device Type" "R402H16"
			(at 0.064008 -5.517896 270)
			(unlocked yes)
			(layer "F.Fab")
			(hide yes)
			(effects
				(font
					(size 1.016 1.016)
					(thickness 0.1524)
				)
			)
		)
		(duplicate_pad_numbers_are_jumpers no)
		(fp_line
			(start -0.508 -0.9398)
			(end -0.508 0.9398)
			(stroke
				(width 0.1524)
				(type default)
			)
			(layer "F.SilkS")
		)
		(fp_line
			(start 0.508 -0.9398)
			(end -0.508 -0.9398)
			(stroke
				(width 0.1524)
				(type default)
			)
			(layer "F.SilkS")
		)
		(fp_rect
			(start -0.508 0.9398)
			(end 0.508 -0.9398)
			(stroke
				(width 0)
				(type default)
			)
			(fill no)
			(layer "F.CrtYd")
		)
		(fp_rect
			(start -0.508 0.9398)
			(end 0.508 -0.9398)
			(stroke
				(width 0)
				(type default)
			)
			(fill no)
			(layer "F.Fab")
		)
		(pad "1" smd custom
			(at 0 -0.4445 270)
			(size 0.1397 0.1397)
			(layers "F.Cu" "F.Mask" "F.Paste")
			(net "P1V8_C_G")
			(options
				(clearance outline)
				(anchor circle)
			)
			(primitives
				(gr_poly
					(pts
						(arc
							(start -0.1778 -0.2794)
							(mid -0.249642 -0.249642)
							(end -0.2794 -0.1778)
						)
						(arc
							(start -0.2794 0.1778)
							(mid -0.249642 0.249642)
							(end -0.1778 0.2794)
						)
						(arc
							(start 0.1778 0.2794)
							(mid 0.249642 0.249642)
							(end 0.2794 0.1778)
						)
						(arc
							(start 0.2794 -0.1778)
							(mid 0.249642 -0.249642)
							(end 0.1778 -0.2794)
						)
					)
					(width 0)
					(fill yes)
				)
			)
		)
		(pad "2" smd custom
			(at 0 0.4445 270)
			(size 0.1397 0.1397)
			(layers "F.Cu" "F.Mask" "F.Paste")
			(net "P1V8_C")
			(options
				(clearance outline)
				(anchor circle)
			)
			(primitives
				(gr_poly
					(pts
						(arc
							(start -0.1778 -0.2794)
							(mid -0.249642 -0.249642)
							(end -0.2794 -0.1778)
						)
						(arc
							(start -0.2794 0.1778)
							(mid -0.249642 0.249642)
							(end -0.1778 0.2794)
						)
						(arc
							(start 0.1778 0.2794)
							(mid 0.249642 0.249642)
							(end 0.2794 0.1778)
						)
						(arc
							(start 0.2794 -0.1778)
							(mid 0.249642 -0.249642)
							(end 0.1778 -0.2794)
						)
					)
					(width 0)
					(fill yes)
				)
			)
		)
	)
	(footprint ""
		(layer "F.Cu")
		(at 156.718 -120.523)
		(property "Reference" "R311"
			(at 0 0 0)
			(layer "F.SilkS")
			(hide yes)
			(effects
				(font
					(size 1.27 1.27)
				)
			)
		)
		(property "Value" "619KR2F-GP"
			(at 0.064008 -3.993896 0)
			(unlocked yes)
			(layer "F.Fab")
			(hide yes)
			(effects
				(font
					(size 1.016 1.016)
					(thickness 0.1524)
				)
			)
		)
		(property "Device Type" "R402H16"
			(at 0.064008 -5.517896 0)
			(unlocked yes)
			(layer "F.Fab")
			(hide yes)
			(effects
				(font
					(size 1.016 1.016)
					(thickness 0.1524)
				)
			)
		)
		(duplicate_pad_numbers_are_jumpers no)
		(fp_line
			(start -0.508 -0.9398)
			(end -0.508 0.9398)
			(stroke
				(width 0.1524)
				(type default)
			)
			(layer "F.SilkS")
		)
		(fp_line
			(start 0.508 -0.9398)
			(end -0.508 -0.9398)
			(stroke
				(width 0.1524)
				(type default)
			)
			(layer "F.SilkS")
		)
		(fp_rect
			(start -0.508 0.9398)
			(end 0.508 -0.9398)
			(stroke
				(width 0)
				(type default)
			)
			(fill no)
			(layer "F.CrtYd")
		)
		(fp_rect
			(start -0.508 0.9398)
			(end 0.508 -0.9398)
			(stroke
				(width 0)
				(type default)
			)
			(fill no)
			(layer "F.Fab")
		)
		(pad "1" smd custom
			(at 0 -0.4445)
			(size 0.1397 0.1397)
			(layers "F.Cu" "F.Mask" "F.Paste")
			(net "AGND_P1V5_E")
			(options
				(clearance outline)
				(anchor circle)
			)
			(primitives
				(gr_poly
					(pts
						(arc
							(start -0.1778 -0.2794)
							(mid -0.249642 -0.249642)
							(end -0.2794 -0.1778)
						)
						(arc
							(start -0.2794 0.1778)
							(mid -0.249642 0.249642)
							(end -0.1778 0.2794)
						)
						(arc
							(start 0.1778 0.2794)
							(mid 0.249642 0.249642)
							(end 0.2794 0.1778)
						)
						(arc
							(start 0.2794 -0.1778)
							(mid 0.249642 -0.249642)
							(end 0.1778 -0.2794)
						)
					)
					(width 0)
					(fill yes)
				)
			)
		)
		(pad "2" smd custom
			(at 0 0.4445)
			(size 0.1397 0.1397)
			(layers "F.Cu" "F.Mask" "F.Paste")
			(net "P1V5_E_RF")
			(options
				(clearance outline)
				(anchor circle)
			)
			(primitives
				(gr_poly
					(pts
						(arc
							(start -0.1778 -0.2794)
							(mid -0.249642 -0.249642)
							(end -0.2794 -0.1778)
						)
						(arc
							(start -0.2794 0.1778)
							(mid -0.249642 0.249642)
							(end -0.1778 0.2794)
						)
						(arc
							(start 0.1778 0.2794)
							(mid 0.249642 0.249642)
							(end 0.2794 0.1778)
						)
						(arc
							(start 0.2794 -0.1778)
							(mid 0.249642 -0.249642)
							(end 0.1778 -0.2794)
						)
					)
					(width 0)
					(fill yes)
				)
			)
		)
	)
	(footprint ""
		(layer "F.Cu")
		(at 65.072514 -94.444058 90)
		(property "Reference" "R503"
			(at 0 0 90)
			(layer "F.SilkS")
			(hide yes)
			(effects
				(font
					(size 1.27 1.27)
				)
			)
		)
		(property "Value" "866KR2F-GP"
			(at 0.064008 -3.993896 90)
			(unlocked yes)
			(layer "F.Fab")
			(hide yes)
			(effects
				(font
					(size 1.016 1.016)
					(thickness 0.1524)
				)
			)
		)
		(property "Device Type" "R402H16"
			(at 0.064008 -5.517896 90)
			(unlocked yes)
			(layer "F.Fab")
			(hide yes)
			(effects
				(font
					(size 1.016 1.016)
					(thickness 0.1524)
				)
			)
		)
		(duplicate_pad_numbers_are_jumpers no)
		(fp_line
			(start 0.508 -0.9398)
			(end -0.508 -0.9398)
			(stroke
				(width 0.1524)
				(type default)
			)
			(layer "F.SilkS")
		)
		(fp_line
			(start -0.508 -0.9398)
			(end -0.508 0.9398)
			(stroke
				(width 0.1524)
				(type default)
			)
			(layer "F.SilkS")
		)
		(fp_rect
			(start -0.508 0.9398)
			(end 0.508 -0.9398)
			(stroke
				(width 0)
				(type default)
			)
			(fill no)
			(layer "F.CrtYd")
		)
		(fp_rect
			(start -0.508 0.9398)
			(end 0.508 -0.9398)
			(stroke
				(width 0)
				(type default)
			)
			(fill no)
			(layer "F.Fab")
		)
		(pad "1" smd custom
			(at 0 -0.4445 90)
			(size 0.1397 0.1397)
			(layers "F.Cu" "F.Mask" "F.Paste")
			(net "P3V3_VREG")
			(options
				(clearance outline)
				(anchor circle)
			)
			(primitives
				(gr_poly
					(pts
						(arc
							(start -0.1778 -0.2794)
							(mid -0.249642 -0.249642)
							(end -0.2794 -0.1778)
						)
						(arc
							(start -0.2794 0.1778)
							(mid -0.249642 0.249642)
							(end -0.1778 0.2794)
						)
						(arc
							(start 0.1778 0.2794)
							(mid 0.249642 0.249642)
							(end 0.2794 0.1778)
						)
						(arc
							(start 0.2794 -0.1778)
							(mid 0.249642 -0.249642)
							(end 0.1778 -0.2794)
						)
					)
					(width 0)
					(fill yes)
				)
			)
		)
		(pad "2" smd custom
			(at 0 0.4445 90)
			(size 0.1397 0.1397)
			(layers "F.Cu" "F.Mask" "F.Paste")
			(net "P3V3_RF")
			(options
				(clearance outline)
				(anchor circle)
			)
			(primitives
				(gr_poly
					(pts
						(arc
							(start -0.1778 -0.2794)
							(mid -0.249642 -0.249642)
							(end -0.2794 -0.1778)
						)
						(arc
							(start -0.2794 0.1778)
							(mid -0.249642 0.249642)
							(end -0.1778 0.2794)
						)
						(arc
							(start 0.1778 0.2794)
							(mid 0.249642 0.249642)
							(end 0.2794 0.1778)
						)
						(arc
							(start 0.2794 -0.1778)
							(mid 0.249642 -0.249642)
							(end 0.1778 -0.2794)
						)
					)
					(width 0)
					(fill yes)
				)
			)
		)
	)
	(footprint ""
		(layer "F.Cu")
		(at 134.99973 -134.999984)
		(property "Reference" ""
			(at 0 0 0)
			(layer "F.SilkS")
			(hide yes)
			(effects
				(font
					(size 1.27 1.27)
				)
			)
		)
		(property "Value" "*"
			(at -6.38175 0.19685 0)
			(unlocked yes)
			(layer "F.Fab")
			(hide yes)
			(effects
				(font
					(size 1.016 1.016)
					(thickness 0.1524)
				)
			)
		)
		(duplicate_pad_numbers_are_jumpers no)
		(fp_poly
			(pts
				(arc
					(start 5.0673 0)
					(mid -5.0673 0)
					(end 5.0673 0)
				)
			)
			(stroke
				(width 0)
				(type default)
			)
			(fill no)
			(layer "B.CrtYd")
		)
		(fp_poly
			(pts
				(arc
					(start 5.0673 0)
					(mid -5.0673 0)
					(end 5.0673 0)
				)
			)
			(stroke
				(width 0)
				(type default)
			)
			(fill no)
			(layer "F.CrtYd")
		)
		(fp_poly
			(pts
				(arc
					(start 5.0673 0)
					(mid -5.0673 0)
					(end 5.0673 0)
				)
			)
			(stroke
				(width 0)
				(type default)
			)
			(fill no)
			(layer "B.Fab")
		)
		(fp_poly
			(pts
				(arc
					(start 5.0673 0)
					(mid -5.0673 0)
					(end 5.0673 0)
				)
			)
			(stroke
				(width 0)
				(type default)
			)
			(fill no)
			(layer "F.Fab")
		)
		(pad "1" thru_hole circle
			(at 0 0)
			(size 9.525 9.525)
			(drill 3.5052)
			(layers "*.Cu" "*.Mask")
			(remove_unused_layers no)
			(net "Net_6")
			(clearance -2.5019)
			(thermal_gap 0.3048)
			(padstack
				(mode front_inner_back)
				(layer "Inner"
					(shape circle)
					(size 3.9116 3.9116)
					(clearance 0.3048)
				)
				(layer "B.Cu"
					(shape circle)
					(size 9.525 9.525)
					(clearance -2.5019)
				)
			)
		)
	)
	(footprint ""
		(layer "F.Cu")
		(at 191.85382 -52.3748 -90)
		(property "Reference" "R215"
			(at 0 0 270)
			(layer "F.SilkS")
			(hide yes)
			(effects
				(font
					(size 1.27 1.27)
				)
			)
		)
		(property "Value" "10KR2F-2-GP"
			(at 0.064008 -3.993896 270)
			(unlocked yes)
			(layer "F.Fab")
			(hide yes)
			(effects
				(font
					(size 1.016 1.016)
					(thickness 0.1524)
				)
			)
		)
		(property "Device Type" "R402H16"
			(at 0.064008 -5.517896 270)
			(unlocked yes)
			(layer "F.Fab")
			(hide yes)
			(effects
				(font
					(size 1.016 1.016)
					(thickness 0.1524)
				)
			)
		)
		(duplicate_pad_numbers_are_jumpers no)
		(fp_line
			(start -0.508 -0.9398)
			(end -0.508 0.9398)
			(stroke
				(width 0.1524)
				(type default)
			)
			(layer "F.SilkS")
		)
		(fp_line
			(start 0.508 -0.9398)
			(end -0.508 -0.9398)
			(stroke
				(width 0.1524)
				(type default)
			)
			(layer "F.SilkS")
		)
		(fp_rect
			(start -0.508 0.9398)
			(end 0.508 -0.9398)
			(stroke
				(width 0)
				(type default)
			)
			(fill no)
			(layer "F.CrtYd")
		)
		(fp_rect
			(start -0.508 0.9398)
			(end 0.508 -0.9398)
			(stroke
				(width 0)
				(type default)
			)
			(fill no)
			(layer "F.Fab")
		)
		(pad "1" smd custom
			(at 0 -0.4445 270)
			(size 0.1397 0.1397)
			(layers "F.Cu" "F.Mask" "F.Paste")
			(net "P1V8_C")
			(options
				(clearance outline)
				(anchor circle)
			)
			(primitives
				(gr_poly
					(pts
						(arc
							(start -0.1778 -0.2794)
							(mid -0.249642 -0.249642)
							(end -0.2794 -0.1778)
						)
						(arc
							(start -0.2794 0.1778)
							(mid -0.249642 0.249642)
							(end -0.1778 0.2794)
						)
						(arc
							(start 0.1778 0.2794)
							(mid 0.249642 0.249642)
							(end 0.2794 0.1778)
						)
						(arc
							(start 0.2794 -0.1778)
							(mid 0.249642 -0.249642)
							(end 0.1778 -0.2794)
						)
					)
					(width 0)
					(fill yes)
				)
			)
		)
		(pad "2" smd custom
			(at 0 0.4445 270)
			(size 0.1397 0.1397)
			(layers "F.Cu" "F.Mask" "F.Paste")
			(net "XM_ADDR_7")
			(options
				(clearance outline)
				(anchor circle)
			)
			(primitives
				(gr_poly
					(pts
						(arc
							(start -0.1778 -0.2794)
							(mid -0.249642 -0.249642)
							(end -0.2794 -0.1778)
						)
						(arc
							(start -0.2794 0.1778)
							(mid -0.249642 0.249642)
							(end -0.1778 0.2794)
						)
						(arc
							(start 0.1778 0.2794)
							(mid 0.249642 0.249642)
							(end 0.2794 0.1778)
						)
						(arc
							(start 0.2794 -0.1778)
							(mid 0.249642 -0.249642)
							(end 0.1778 -0.2794)
						)
					)
					(width 0)
					(fill yes)
				)
			)
		)
	)
	(footprint ""
		(layer "F.Cu")
		(at 62.76975 -123.205494)
		(property "Reference" "R511"
			(at 0 0 0)
			(layer "F.SilkS")
			(hide yes)
			(effects
				(font
					(size 1.27 1.27)
				)
			)
		)
		(property "Value" "0R5J-5-GP"
			(at 0 -8.9535 0)
			(unlocked yes)
			(layer "F.Fab")
			(hide yes)
			(effects
				(font
					(size 1.27 1.016)
					(thickness 0.1524)
				)
			)
		)
		(property "Device Type" "R805H24"
			(at 0 -10.6299 0)
			(unlocked yes)
			(layer "F.Fab")
			(hide yes)
			(effects
				(font
					(size 1.27 1.016)
					(thickness 0.1524)
				)
			)
		)
		(duplicate_pad_numbers_are_jumpers no)
		(fp_line
			(start -0.889 -1.7018)
			(end -0.889 0.2794)
			(stroke
				(width 0.1524)
				(type default)
			)
			(layer "F.SilkS")
		)
		(fp_line
			(start -0.889 0.0762)
			(end -0.889 1.7018)
			(stroke
				(width 0.1524)
				(type default)
			)
			(layer "F.SilkS")
		)
		(fp_line
			(start -0.889 1.7018)
			(end 0.889 1.7018)
			(stroke
				(width 0.1524)
				(type default)
			)
			(layer "F.SilkS")
		)
		(fp_line
			(start 0.889 -1.7018)
			(end -0.889 -1.7018)
			(stroke
				(width 0.1524)
				(type default)
			)
			(layer "F.SilkS")
		)
		(fp_line
			(start 0.889 -1.7018)
			(end 0.889 -0.381)
			(stroke
				(width 0.1524)
				(type default)
			)
			(layer "F.SilkS")
		)
		(fp_line
			(start 0.889 1.7018)
			(end 0.889 -0.508)
			(stroke
				(width 0.1524)
				(type default)
			)
			(layer "F.SilkS")
		)
		(fp_poly
			(pts
				(xy 0.9652 -1.778) (xy 0.9652 1.778) (xy -0.9652 1.778) (xy -0.9652 -1.778)
			)
			(stroke
				(width 0)
				(type default)
			)
			(fill no)
			(layer "F.CrtYd")
		)
		(fp_rect
			(start -0.9652 1.778)
			(end 0.9652 -1.778)
			(stroke
				(width 0)
				(type default)
			)
			(fill no)
			(layer "F.Fab")
		)
		(pad "1" smd rect
			(at 0 -0.9652)
			(size 1.397 1.143)
			(layers "F.Cu" "F.Mask" "F.Paste")
			(net "P3V3")
		)
		(pad "2" smd rect
			(at 0 0.9652)
			(size 1.397 1.143)
			(layers "F.Cu" "F.Mask" "F.Paste")
			(net "P3V3_OUT")
		)
	)
	(footprint ""
		(layer "F.Cu")
		(at 19.2278 -78.613 90)
		(property "Reference" "R347"
			(at 0 0 90)
			(layer "F.SilkS")
			(hide yes)
			(effects
				(font
					(size 1.27 1.27)
				)
			)
		)
		(property "Value" "0R2J-2-GP"
			(at 0.064008 -3.993896 90)
			(unlocked yes)
			(layer "F.Fab")
			(hide yes)
			(effects
				(font
					(size 1.016 1.016)
					(thickness 0.1524)
				)
			)
		)
		(property "Device Type" "R402H16"
			(at 0.064008 -5.517896 90)
			(unlocked yes)
			(layer "F.Fab")
			(hide yes)
			(effects
				(font
					(size 1.016 1.016)
					(thickness 0.1524)
				)
			)
		)
		(duplicate_pad_numbers_are_jumpers no)
		(fp_line
			(start 0.508 -0.9398)
			(end -0.508 -0.9398)
			(stroke
				(width 0.1524)
				(type default)
			)
			(layer "F.SilkS")
		)
		(fp_line
			(start -0.508 -0.9398)
			(end -0.508 0.9398)
			(stroke
				(width 0.1524)
				(type default)
			)
			(layer "F.SilkS")
		)
		(fp_rect
			(start -0.508 0.9398)
			(end 0.508 -0.9398)
			(stroke
				(width 0)
				(type default)
			)
			(fill no)
			(layer "F.CrtYd")
		)
		(fp_rect
			(start -0.508 0.9398)
			(end 0.508 -0.9398)
			(stroke
				(width 0)
				(type default)
			)
			(fill no)
			(layer "F.Fab")
		)
		(pad "1" smd custom
			(at 0 -0.4445 90)
			(size 0.1397 0.1397)
			(layers "F.Cu" "F.Mask" "F.Paste")
			(net "EXP_EEPROM_SCL")
			(options
				(clearance outline)
				(anchor circle)
			)
			(primitives
				(gr_poly
					(pts
						(arc
							(start -0.1778 -0.2794)
							(mid -0.249642 -0.249642)
							(end -0.2794 -0.1778)
						)
						(arc
							(start -0.2794 0.1778)
							(mid -0.249642 0.249642)
							(end -0.1778 0.2794)
						)
						(arc
							(start 0.1778 0.2794)
							(mid 0.249642 0.249642)
							(end 0.2794 0.1778)
						)
						(arc
							(start 0.2794 -0.1778)
							(mid 0.249642 -0.249642)
							(end 0.1778 -0.2794)
						)
					)
					(width 0)
					(fill yes)
				)
			)
		)
		(pad "2" smd custom
			(at 0 0.4445 90)
			(size 0.1397 0.1397)
			(layers "F.Cu" "F.Mask" "F.Paste")
			(net "I2C_SCC_SCL2")
			(options
				(clearance outline)
				(anchor circle)
			)
			(primitives
				(gr_poly
					(pts
						(arc
							(start -0.1778 -0.2794)
							(mid -0.249642 -0.249642)
							(end -0.2794 -0.1778)
						)
						(arc
							(start -0.2794 0.1778)
							(mid -0.249642 0.249642)
							(end -0.1778 0.2794)
						)
						(arc
							(start 0.1778 0.2794)
							(mid 0.249642 0.249642)
							(end 0.2794 0.1778)
						)
						(arc
							(start 0.2794 -0.1778)
							(mid 0.249642 -0.249642)
							(end 0.1778 -0.2794)
						)
					)
					(width 0)
					(fill yes)
				)
			)
		)
	)
)
